(kicad_pcb
	(version 20260206)
	(generator "pcbnew")
	(generator_version "10.0")
	(general
		(thickness 1.6)
		(legacy_teardrops no)
	)
	(paper "A4")
	(title_block
		(title "12092022_DA0F0TFB6D0_F0T_FAN_BOARD_MP5048_D_brd_v02_OCP.brd")
		(comment 1 "Grand Teton / footprints 578-583 of 924")
	)
	(layers
		(0 "F.Cu" signal "TOP")
		(4 "In1.Cu" signal "GND")
		(6 "In2.Cu" signal "IN1")
		(8 "In3.Cu" signal "IN2")
		(10 "In4.Cu" signal "GND1")
		(2 "B.Cu" signal "BOTTOM")
		(9 "F.Adhes" user "F.Adhesive")
		(11 "B.Adhes" user "B.Adhesive")
		(13 "F.Paste" user "Package Geometry/Pastemask Top")
		(15 "B.Paste" user "Package Geometry/Pastemask Bottom")
		(5 "F.SilkS" user "Ref Des/Silkscreen Top")
		(7 "B.SilkS" user "Ref Des/Silkscreen Bottom")
		(1 "F.Mask" user "Board Geometry/Soldermask Top")
		(3 "B.Mask" user "Board Geometry/Soldermask Bottom")
		(17 "Dwgs.User" user "User.Drawings")
		(19 "Cmts.User" user "User.Comments")
		(21 "Eco1.User" user "User.Eco1")
		(23 "Eco2.User" user "User.Eco2")
		(25 "Edge.Cuts" user "Board Geometry/Outline")
		(27 "Margin" user)
		(31 "F.CrtYd" user "Package Geometry/Place Bound Top")
		(29 "B.CrtYd" user "Package Geometry/Place Bound Bottom")
		(35 "F.Fab" user "Ref Des/Assembly Top")
		(33 "B.Fab" user "Ref Des/Assembly Bottom")
	)
	(footprint ""
		(layer "F.Cu")
		(at 32.766 -210.594956)
		(property "Reference" "R5304"
			(at 0 0 0)
			(layer "F.SilkS")
			(hide yes)
			(effects
				(font
					(size 1.27 1.27)
				)
			)
		)
		(property "Value" ""
			(at 0 0 0)
			(layer "F.Fab")
			(effects
				(font
					(size 1.27 1.27)
				)
			)
		)
		(duplicate_pad_numbers_are_jumpers no)
		(fp_line
			(start -1.2954 -0.5842)
			(end 1.2954 -0.5842)
			(stroke
				(width 0.1524)
				(type default)
			)
			(layer "F.SilkS")
		)
		(fp_line
			(start -1.2954 0.5842)
			(end -1.2954 -0.5842)
			(stroke
				(width 0.1524)
				(type default)
			)
			(layer "F.SilkS")
		)
		(fp_line
			(start 1.2954 -0.5842)
			(end 1.2954 0.5842)
			(stroke
				(width 0.1524)
				(type default)
			)
			(layer "F.SilkS")
		)
		(fp_line
			(start 1.2954 0.5842)
			(end -1.2954 0.5842)
			(stroke
				(width 0.1524)
				(type default)
			)
			(layer "F.SilkS")
		)
		(fp_line
			(start -1.1938 -0.406654)
			(end -0.8636 -0.406654)
			(stroke
				(width 0.1)
				(type default)
			)
			(layer "F.Fab")
		)
		(fp_line
			(start -1.1938 0.4064)
			(end -1.1938 -0.406654)
			(stroke
				(width 0.1)
				(type default)
			)
			(layer "F.Fab")
		)
		(fp_line
			(start -0.8636 -0.4572)
			(end 0.8636 -0.4572)
			(stroke
				(width 0.1)
				(type default)
			)
			(layer "F.Fab")
		)
		(fp_line
			(start -0.8636 -0.406654)
			(end -0.8636 -0.4572)
			(stroke
				(width 0.1)
				(type default)
			)
			(layer "F.Fab")
		)
		(fp_line
			(start -0.8636 0.4064)
			(end -1.1938 0.4064)
			(stroke
				(width 0.1)
				(type default)
			)
			(layer "F.Fab")
		)
		(fp_line
			(start -0.8636 0.4318)
			(end -0.8636 0.4064)
			(stroke
				(width 0.1)
				(type default)
			)
			(layer "F.Fab")
		)
		(fp_line
			(start -0.8636 0.4572)
			(end -0.8636 0.4318)
			(stroke
				(width 0.1)
				(type default)
			)
			(layer "F.Fab")
		)
		(fp_line
			(start 0.8636 -0.4572)
			(end 0.8636 -0.406654)
			(stroke
				(width 0.1)
				(type default)
			)
			(layer "F.Fab")
		)
		(fp_line
			(start 0.8636 -0.406654)
			(end 1.1938 -0.406654)
			(stroke
				(width 0.1)
				(type default)
			)
			(layer "F.Fab")
		)
		(fp_line
			(start 0.8636 0.4064)
			(end 0.8636 0.4572)
			(stroke
				(width 0.1)
				(type default)
			)
			(layer "F.Fab")
		)
		(fp_line
			(start 0.8636 0.4572)
			(end -0.8636 0.4572)
			(stroke
				(width 0.1)
				(type default)
			)
			(layer "F.Fab")
		)
		(fp_line
			(start 1.1938 -0.406654)
			(end 1.1938 0.4064)
			(stroke
				(width 0.1)
				(type default)
			)
			(layer "F.Fab")
		)
		(fp_line
			(start 1.1938 0.4064)
			(end 0.8636 0.4064)
			(stroke
				(width 0.1)
				(type default)
			)
			(layer "F.Fab")
		)
		(pad "1" smd rect
			(at -0.7366 0 270)
			(size 0.7112 0.8128)
			(layers "F.Cu" "F.Mask" "F.Paste")
			(net "P52V_FAN_1")
		)
		(pad "2" smd rect
			(at 0.7366 0 270)
			(size 0.7112 0.8128)
			(layers "F.Cu" "F.Mask" "F.Paste")
			(net "FAN_1_TACH_IL_R")
		)
	)
	(footprint ""
		(layer "F.Cu")
		(at 36.322 -28.661868)
		(property "Reference" "D284"
			(at 3.302 0.875538 0)
			(unlocked yes)
			(layer "F.SilkS")
			(effects
				(font
					(size 0.7874 0.5842)
					(thickness 0.1524)
				)
				(justify left)
			)
		)
		(property "Value" ""
			(at 0 0 0)
			(layer "F.Fab")
			(effects
				(font
					(size 1.27 1.27)
				)
			)
		)
		(duplicate_pad_numbers_are_jumpers no)
		(fp_line
			(start -0.854964 -0.450088)
			(end -0.854964 0.450088)
			(stroke
				(width 0.1524)
				(type default)
			)
			(layer "F.SilkS")
		)
		(fp_line
			(start -0.854964 0.450088)
			(end 0.925068 0.450088)
			(stroke
				(width 0.1524)
				(type default)
			)
			(layer "F.SilkS")
		)
		(fp_line
			(start 0.845058 0.4064)
			(end 0.845058 -0.381)
			(stroke
				(width 0.1524)
				(type default)
			)
			(layer "F.SilkS")
		)
		(fp_line
			(start 0.870458 -0.2794)
			(end 0.845058 0.4064)
			(stroke
				(width 0.1524)
				(type default)
			)
			(layer "F.SilkS")
		)
		(fp_line
			(start 0.94488 -0.450088)
			(end -0.854964 -0.450088)
			(stroke
				(width 0.1524)
				(type default)
			)
			(layer "F.SilkS")
		)
		(fp_line
			(start 0.94488 0.450088)
			(end 0.94488 -0.450088)
			(stroke
				(width 0.1524)
				(type default)
			)
			(layer "F.SilkS")
		)
		(fp_line
			(start -0.54991 -0.350012)
			(end -0.54991 0.350012)
			(stroke
				(width 0.1)
				(type default)
			)
			(layer "F.Fab")
		)
		(fp_line
			(start -0.54991 0.350012)
			(end 0.54991 0.350012)
			(stroke
				(width 0.1)
				(type default)
			)
			(layer "F.Fab")
		)
		(fp_line
			(start 0.54991 -0.350012)
			(end -0.54991 -0.350012)
			(stroke
				(width 0.1)
				(type default)
			)
			(layer "F.Fab")
		)
		(fp_line
			(start 0.54991 0.350012)
			(end 0.54991 -0.350012)
			(stroke
				(width 0.1)
				(type default)
			)
			(layer "F.Fab")
		)
		(fp_text user "+"
			(at -0.635 0.309118 180)
			(unlocked yes)
			(layer "F.SilkS")
			(effects
				(font
					(size 1.905 1.4224)
					(thickness 0.1524)
				)
				(justify left)
			)
		)
		(fp_text user "-"
			(at 2.159 0.309118 180)
			(unlocked yes)
			(layer "F.SilkS")
			(effects
				(font
					(size 1.905 1.4224)
					(thickness 0.1524)
				)
				(justify left)
			)
		)
		(fp_text user "+"
			(at -0.808228 0.239014 180)
			(unlocked yes)
			(layer "F.Fab")
			(effects
				(font
					(size 1.905 1.4224)
					(thickness 0.1524)
				)
				(justify left)
			)
		)
		(fp_text user "-"
			(at 2.48539 0.239014 180)
			(unlocked yes)
			(layer "F.Fab")
			(effects
				(font
					(size 1.905 1.4224)
					(thickness 0.1524)
				)
				(justify left)
			)
		)
		(pad "A" smd rect
			(at -0.424942 0)
			(size 0.5588 0.6096)
			(layers "F.Cu" "F.Mask" "F.Paste")
			(net "GND")
		)
		(pad "C" smd rect
			(at 0.424942 0 180)
			(size 0.5588 0.6096)
			(layers "F.Cu" "F.Mask" "F.Paste")
			(net "FAN_3_TACH_IL_D")
		)
	)
	(footprint ""
		(layer "F.Cu")
		(at 37.846 -135.128 180)
		(property "Reference" "R5599"
			(at 0 0 180)
			(layer "F.SilkS")
			(hide yes)
			(effects
				(font
					(size 1.27 1.27)
				)
			)
		)
		(property "Value" ""
			(at 0 0 180)
			(layer "F.Fab")
			(effects
				(font
					(size 1.27 1.27)
				)
			)
		)
		(duplicate_pad_numbers_are_jumpers no)
		(fp_line
			(start 0.7874 0.4064)
			(end -0.7874 0.4064)
			(stroke
				(width 0.1524)
				(type default)
			)
			(layer "F.SilkS")
		)
		(fp_line
			(start 0.7874 -0.4064)
			(end 0.7874 0.4064)
			(stroke
				(width 0.1524)
				(type default)
			)
			(layer "F.SilkS")
		)
		(fp_line
			(start -0.7874 0.4064)
			(end -0.7874 -0.4064)
			(stroke
				(width 0.1524)
				(type default)
			)
			(layer "F.SilkS")
		)
		(fp_line
			(start -0.7874 -0.4064)
			(end 0.7874 -0.4064)
			(stroke
				(width 0.1524)
				(type default)
			)
			(layer "F.SilkS")
		)
		(fp_line
			(start 0.67945 0.3048)
			(end 0.120396 0.3048)
			(stroke
				(width 0.1)
				(type default)
			)
			(layer "F.Fab")
		)
		(fp_line
			(start 0.67945 -0.3048)
			(end 0.67945 0.3048)
			(stroke
				(width 0.1)
				(type default)
			)
			(layer "F.Fab")
		)
		(fp_line
			(start 0.12065 -0.2794)
			(end 0.12065 -0.3048)
			(stroke
				(width 0.1)
				(type default)
			)
			(layer "F.Fab")
		)
		(fp_line
			(start 0.12065 -0.3048)
			(end 0.67945 -0.3048)
			(stroke
				(width 0.1)
				(type default)
			)
			(layer "F.Fab")
		)
		(fp_line
			(start 0.120396 0.3048)
			(end 0.120396 0.2794)
			(stroke
				(width 0.1)
				(type default)
			)
			(layer "F.Fab")
		)
		(fp_line
			(start 0.120396 0.2794)
			(end -0.12065 0.2794)
			(stroke
				(width 0.1)
				(type default)
			)
			(layer "F.Fab")
		)
		(fp_line
			(start -0.12065 0.3048)
			(end -0.67945 0.3048)
			(stroke
				(width 0.1)
				(type default)
			)
			(layer "F.Fab")
		)
		(fp_line
			(start -0.12065 0.2794)
			(end -0.12065 0.3048)
			(stroke
				(width 0.1)
				(type default)
			)
			(layer "F.Fab")
		)
		(fp_line
			(start -0.12065 -0.2794)
			(end 0.12065 -0.2794)
			(stroke
				(width 0.1)
				(type default)
			)
			(layer "F.Fab")
		)
		(fp_line
			(start -0.12065 -0.305054)
			(end -0.12065 -0.2794)
			(stroke
				(width 0.1)
				(type default)
			)
			(layer "F.Fab")
		)
		(fp_line
			(start -0.67945 0.3048)
			(end -0.67945 -0.305054)
			(stroke
				(width 0.1)
				(type default)
			)
			(layer "F.Fab")
		)
		(fp_line
			(start -0.67945 -0.305054)
			(end -0.12065 -0.305054)
			(stroke
				(width 0.1)
				(type default)
			)
			(layer "F.Fab")
		)
		(pad "1" smd rect
			(at -0.40005 0)
			(size 0.4572 0.508)
			(layers "F.Cu" "F.Mask" "F.Paste")
			(net "FAN_1_TACH_IL")
		)
		(pad "2" smd rect
			(at 0.40005 0)
			(size 0.4572 0.508)
			(layers "F.Cu" "F.Mask" "F.Paste")
			(net "FAN_1_TACH_IL_R1")
		)
	)
	(footprint ""
		(layer "F.Cu")
		(at 33.274 -185.039 180)
		(property "Reference" "R513"
			(at 0 0 180)
			(layer "F.SilkS")
			(hide yes)
			(effects
				(font
					(size 1.27 1.27)
				)
			)
		)
		(property "Value" ""
			(at 0 0 180)
			(layer "F.Fab")
			(effects
				(font
					(size 1.27 1.27)
				)
			)
		)
		(duplicate_pad_numbers_are_jumpers no)
		(fp_line
			(start 0.7874 0.4064)
			(end -0.7874 0.4064)
			(stroke
				(width 0.1524)
				(type default)
			)
			(layer "F.SilkS")
		)
		(fp_line
			(start 0.7874 -0.4064)
			(end 0.7874 0.4064)
			(stroke
				(width 0.1524)
				(type default)
			)
			(layer "F.SilkS")
		)
		(fp_line
			(start -0.7874 0.4064)
			(end -0.7874 -0.4064)
			(stroke
				(width 0.1524)
				(type default)
			)
			(layer "F.SilkS")
		)
		(fp_line
			(start -0.7874 -0.4064)
			(end 0.7874 -0.4064)
			(stroke
				(width 0.1524)
				(type default)
			)
			(layer "F.SilkS")
		)
		(fp_line
			(start 0.67945 0.3048)
			(end 0.120396 0.3048)
			(stroke
				(width 0.1)
				(type default)
			)
			(layer "F.Fab")
		)
		(fp_line
			(start 0.67945 -0.3048)
			(end 0.67945 0.3048)
			(stroke
				(width 0.1)
				(type default)
			)
			(layer "F.Fab")
		)
		(fp_line
			(start 0.12065 -0.2794)
			(end 0.12065 -0.3048)
			(stroke
				(width 0.1)
				(type default)
			)
			(layer "F.Fab")
		)
		(fp_line
			(start 0.12065 -0.3048)
			(end 0.67945 -0.3048)
			(stroke
				(width 0.1)
				(type default)
			)
			(layer "F.Fab")
		)
		(fp_line
			(start 0.120396 0.3048)
			(end 0.120396 0.2794)
			(stroke
				(width 0.1)
				(type default)
			)
			(layer "F.Fab")
		)
		(fp_line
			(start 0.120396 0.2794)
			(end -0.12065 0.2794)
			(stroke
				(width 0.1)
				(type default)
			)
			(layer "F.Fab")
		)
		(fp_line
			(start -0.12065 0.3048)
			(end -0.67945 0.3048)
			(stroke
				(width 0.1)
				(type default)
			)
			(layer "F.Fab")
		)
		(fp_line
			(start -0.12065 0.2794)
			(end -0.12065 0.3048)
			(stroke
				(width 0.1)
				(type default)
			)
			(layer "F.Fab")
		)
		(fp_line
			(start -0.12065 -0.2794)
			(end 0.12065 -0.2794)
			(stroke
				(width 0.1)
				(type default)
			)
			(layer "F.Fab")
		)
		(fp_line
			(start -0.12065 -0.305054)
			(end -0.12065 -0.2794)
			(stroke
				(width 0.1)
				(type default)
			)
			(layer "F.Fab")
		)
		(fp_line
			(start -0.67945 0.3048)
			(end -0.67945 -0.305054)
			(stroke
				(width 0.1)
				(type default)
			)
			(layer "F.Fab")
		)
		(fp_line
			(start -0.67945 -0.305054)
			(end -0.12065 -0.305054)
			(stroke
				(width 0.1)
				(type default)
			)
			(layer "F.Fab")
		)
		(pad "1" smd circle
			(at -0.40005 0 180)
			(size 0 0)
			(layers "F.Cu" "F.Mask" "F.Paste")
			(net "P52V_FAN_BUFF_EN_R")
		)
		(pad "2" smd circle
			(at 0.40005 0 180)
			(size 0 0)
			(layers "F.Cu" "F.Mask" "F.Paste")
			(net "P52V_FAN_EN")
		)
	)
	(footprint ""
		(layer "F.Cu")
		(at 37.338 -295.91)
		(property "Reference" "R5689"
			(at 0 0 0)
			(layer "F.SilkS")
			(hide yes)
			(effects
				(font
					(size 1.27 1.27)
				)
			)
		)
		(property "Value" ""
			(at 0 0 0)
			(layer "F.Fab")
			(effects
				(font
					(size 1.27 1.27)
				)
			)
		)
		(duplicate_pad_numbers_are_jumpers no)
		(fp_line
			(start -0.7874 -0.4064)
			(end 0.7874 -0.4064)
			(stroke
				(width 0.1524)
				(type default)
			)
			(layer "F.SilkS")
		)
		(fp_line
			(start -0.7874 0.4064)
			(end -0.7874 -0.4064)
			(stroke
				(width 0.1524)
				(type default)
			)
			(layer "F.SilkS")
		)
		(fp_line
			(start 0.7874 -0.4064)
			(end 0.7874 0.4064)
			(stroke
				(width 0.1524)
				(type default)
			)
			(layer "F.SilkS")
		)
		(fp_line
			(start 0.7874 0.4064)
			(end -0.7874 0.4064)
			(stroke
				(width 0.1524)
				(type default)
			)
			(layer "F.SilkS")
		)
		(fp_line
			(start -0.67945 -0.305054)
			(end -0.12065 -0.305054)
			(stroke
				(width 0.1)
				(type default)
			)
			(layer "F.Fab")
		)
		(fp_line
			(start -0.67945 0.3048)
			(end -0.67945 -0.305054)
			(stroke
				(width 0.1)
				(type default)
			)
			(layer "F.Fab")
		)
		(fp_line
			(start -0.12065 -0.305054)
			(end -0.12065 -0.2794)
			(stroke
				(width 0.1)
				(type default)
			)
			(layer "F.Fab")
		)
		(fp_line
			(start -0.12065 -0.2794)
			(end 0.12065 -0.2794)
			(stroke
				(width 0.1)
				(type default)
			)
			(layer "F.Fab")
		)
		(fp_line
			(start -0.12065 0.2794)
			(end -0.12065 0.3048)
			(stroke
				(width 0.1)
				(type default)
			)
			(layer "F.Fab")
		)
		(fp_line
			(start -0.12065 0.3048)
			(end -0.67945 0.3048)
			(stroke
				(width 0.1)
				(type default)
			)
			(layer "F.Fab")
		)
		(fp_line
			(start 0.120396 0.2794)
			(end -0.12065 0.2794)
			(stroke
				(width 0.1)
				(type default)
			)
			(layer "F.Fab")
		)
		(fp_line
			(start 0.120396 0.3048)
			(end 0.120396 0.2794)
			(stroke
				(width 0.1)
				(type default)
			)
			(layer "F.Fab")
		)
		(fp_line
			(start 0.12065 -0.3048)
			(end 0.67945 -0.3048)
			(stroke
				(width 0.1)
				(type default)
			)
			(layer "F.Fab")
		)
		(fp_line
			(start 0.12065 -0.2794)
			(end 0.12065 -0.3048)
			(stroke
				(width 0.1)
				(type default)
			)
			(layer "F.Fab")
		)
		(fp_line
			(start 0.67945 -0.3048)
			(end 0.67945 0.3048)
			(stroke
				(width 0.1)
				(type default)
			)
			(layer "F.Fab")
		)
		(fp_line
			(start 0.67945 0.3048)
			(end 0.120396 0.3048)
			(stroke
				(width 0.1)
				(type default)
			)
			(layer "F.Fab")
		)
		(pad "1" smd rect
			(at -0.40005 0 180)
			(size 0.4572 0.508)
			(layers "F.Cu" "F.Mask" "F.Paste")
			(net "P12V_LED_FAN0")
		)
		(pad "2" smd rect
			(at 0.40005 0 180)
			(size 0.4572 0.508)
			(layers "F.Cu" "F.Mask" "F.Paste")
			(net "P12V_LED_R_FAN0")
		)
	)
	(footprint ""
		(layer "F.Cu")
		(at 30.353 -187.452)
		(property "Reference" "R4956"
			(at 0 0 0)
			(layer "F.SilkS")
			(hide yes)
			(effects
				(font
					(size 1.27 1.27)
				)
			)
		)
		(property "Value" ""
			(at 0 0 0)
			(layer "F.Fab")
			(effects
				(font
					(size 1.27 1.27)
				)
			)
		)
		(duplicate_pad_numbers_are_jumpers no)
		(fp_line
			(start -0.7874 -0.4064)
			(end 0.7874 -0.4064)
			(stroke
				(width 0.1524)
				(type default)
			)
			(layer "F.SilkS")
		)
		(fp_line
			(start -0.7874 0.4064)
			(end -0.7874 -0.4064)
			(stroke
				(width 0.1524)
				(type default)
			)
			(layer "F.SilkS")
		)
		(fp_line
			(start 0.7874 -0.4064)
			(end 0.7874 0.4064)
			(stroke
				(width 0.1524)
				(type default)
			)
			(layer "F.SilkS")
		)
		(fp_line
			(start 0.7874 0.4064)
			(end -0.7874 0.4064)
			(stroke
				(width 0.1524)
				(type default)
			)
			(layer "F.SilkS")
		)
		(fp_line
			(start -0.67945 -0.305054)
			(end -0.12065 -0.305054)
			(stroke
				(width 0.1)
				(type default)
			)
			(layer "F.Fab")
		)
		(fp_line
			(start -0.67945 0.3048)
			(end -0.67945 -0.305054)
			(stroke
				(width 0.1)
				(type default)
			)
			(layer "F.Fab")
		)
		(fp_line
			(start -0.12065 -0.305054)
			(end -0.12065 -0.2794)
			(stroke
				(width 0.1)
				(type default)
			)
			(layer "F.Fab")
		)
		(fp_line
			(start -0.12065 -0.2794)
			(end 0.12065 -0.2794)
			(stroke
				(width 0.1)
				(type default)
			)
			(layer "F.Fab")
		)
		(fp_line
			(start -0.12065 0.2794)
			(end -0.12065 0.3048)
			(stroke
				(width 0.1)
				(type default)
			)
			(layer "F.Fab")
		)
		(fp_line
			(start -0.12065 0.3048)
			(end -0.67945 0.3048)
			(stroke
				(width 0.1)
				(type default)
			)
			(layer "F.Fab")
		)
		(fp_line
			(start 0.120396 0.2794)
			(end -0.12065 0.2794)
			(stroke
				(width 0.1)
				(type default)
			)
			(layer "F.Fab")
		)
		(fp_line
			(start 0.120396 0.3048)
			(end 0.120396 0.2794)
			(stroke
				(width 0.1)
				(type default)
			)
			(layer "F.Fab")
		)
		(fp_line
			(start 0.12065 -0.3048)
			(end 0.67945 -0.3048)
			(stroke
				(width 0.1)
				(type default)
			)
			(layer "F.Fab")
		)
		(fp_line
			(start 0.12065 -0.2794)
			(end 0.12065 -0.3048)
			(stroke
				(width 0.1)
				(type default)
			)
			(layer "F.Fab")
		)
		(fp_line
			(start 0.67945 -0.3048)
			(end 0.67945 0.3048)
			(stroke
				(width 0.1)
				(type default)
			)
			(layer "F.Fab")
		)
		(fp_line
			(start 0.67945 0.3048)
			(end 0.120396 0.3048)
			(stroke
				(width 0.1)
				(type default)
			)
			(layer "F.Fab")
		)
		(pad "1" smd circle
			(at -0.40005 0)
			(size 0 0)
			(layers "F.Cu" "F.Mask" "F.Paste")
			(net "P3V3_AUX")
		)
		(pad "2" smd circle
			(at 0.40005 0)
			(size 0 0)
			(layers "F.Cu" "F.Mask" "F.Paste")
			(net "P52V_FAN_5_BUFF_EN")
		)
	)
)
